(kicad_pcb
	(version 20240108)
	(generator "pcbnew")
	(generator_version "8.0")
	(general
		(thickness 1.6)
		(legacy_teardrops no)
	)
	(paper "A4")
	(title_block
		(title "Jetson Orin Baseboard OCuLink Expansion")
		(date "2025-03-18")
		(rev "1.1.0")
		(company "Antmicro Ltd")
		(comment 1 "www.antmicro.com")
		(comment 9 "footprints 44-48 of 119")
	)
	(layers
		(0 "F.Cu" signal)
		(1 "In1.Cu" signal)
		(2 "In2.Cu" signal)
		(31 "B.Cu" signal)
		(32 "B.Adhes" user "B.Adhesive")
		(33 "F.Adhes" user "F.Adhesive")
		(34 "B.Paste" user)
		(35 "F.Paste" user)
		(36 "B.SilkS" user "B.Silkscreen")
		(37 "F.SilkS" user "F.Silkscreen")
		(38 "B.Mask" user)
		(39 "F.Mask" user)
		(40 "Dwgs.User" user "User.Drawings")
		(41 "Cmts.User" user "User.Comments")
		(42 "Eco1.User" user "User.Eco1")
		(43 "Eco2.User" user "User.Eco2")
		(44 "Edge.Cuts" user)
		(45 "Margin" user)
		(46 "B.CrtYd" user "B.Courtyard")
		(47 "F.CrtYd" user "F.Courtyard")
		(48 "B.Fab" user)
		(49 "F.Fab" user)
	)
	(footprint "antmicro-footprints:R_0402_1005Metric"
		(layer "F.Cu")
		(at 146.2 116.979 -90)
		(descr "Resistor SMD 0402")
		(tags "resistor SMD 0402")
		(property "Reference" "R49"
			(at -1.079 -0.4 -90)
			(layer "F.SilkS")
			(effects
				(font
					(size 0.7 0.7)
					(thickness 0.15)
				)
				(justify right top)
			)
		)
		(property "Value" "R_0R_0402"
			(at -1.011843 1.772047 90)
			(layer "F.Fab")
			(effects
				(font
					(size 0.7 0.7)
					(thickness 0.15)
				)
				(justify right top)
			)
		)
		(property "Footprint" "antmicro-footprints:R_0402_1005Metric"
			(at 0 0 90)
			(layer "F.Fab")
			(hide yes)
			(effects
				(font
					(size 1.27 1.27)
					(thickness 0.15)
				)
			)
		)
		(property "Datasheet" "https://industrial.panasonic.com/cdbs/www-data/pdf/RDA0000/AOA0000C301.pdf"
			(at 0 0 90)
			(layer "F.Fab")
			(hide yes)
			(effects
				(font
					(size 1.27 1.27)
					(thickness 0.15)
				)
			)
		)
		(property "Description" "SMD Chip Resistor, Jumper, 0 ohm, 100 mW, 0402 [1005 Metric], Thick Film, General Purpose"
			(at 0 0 90)
			(layer "F.Fab")
			(hide yes)
			(effects
				(font
					(size 1.27 1.27)
					(thickness 0.15)
				)
			)
		)
		(property "MPN" "ERJ2GE0R00X"
			(at 0 0 -90)
			(unlocked yes)
			(layer "F.Fab")
			(hide yes)
			(effects
				(font
					(size 1 1)
					(thickness 0.15)
				)
			)
		)
		(property "Manufacturer" "Panasonic"
			(at 0 0 -90)
			(unlocked yes)
			(layer "F.Fab")
			(hide yes)
			(effects
				(font
					(size 1 1)
					(thickness 0.15)
				)
			)
		)
		(property "License" "Apache-2.0"
			(at 0 0 -90)
			(unlocked yes)
			(layer "F.Fab")
			(hide yes)
			(effects
				(font
					(size 1 1)
					(thickness 0.15)
				)
			)
		)
		(property "Author" "Antmicro"
			(at 0 0 -90)
			(unlocked yes)
			(layer "F.Fab")
			(hide yes)
			(effects
				(font
					(size 1 1)
					(thickness 0.15)
				)
			)
		)
		(property "Val" "0R"
			(at 0 0 -90)
			(unlocked yes)
			(layer "F.Fab")
			(hide yes)
			(effects
				(font
					(size 1 1)
					(thickness 0.15)
				)
			)
		)
		(property "Tolerance" ""
			(at 0 0 -90)
			(unlocked yes)
			(layer "F.Fab")
			(hide yes)
			(effects
				(font
					(size 1 1)
					(thickness 0.15)
				)
			)
		)
		(property "Current" "1A"
			(at 0 0 -90)
			(unlocked yes)
			(layer "F.Fab")
			(hide yes)
			(effects
				(font
					(size 1 1)
					(thickness 0.15)
				)
			)
		)
		(sheetname "Root")
		(sheetfile "jetson-orin-baseboard-oculink-expansion.kicad_sch")
		(attr smd)
		(fp_rect
			(start -0.925 -0.47)
			(end 0.925 0.47)
			(stroke
				(width 0.05)
				(type default)
			)
			(fill none)
			(layer "F.CrtYd")
		)
		(fp_rect
			(start -0.5 -0.25)
			(end 0.5 0.25)
			(stroke
				(width 0.15)
				(type solid)
			)
			(fill none)
			(layer "F.Fab")
		)
		(fp_text user "Author: Antmicro"
			(at -0.95 4.169 90)
			(layer "F.Fab")
			(hide yes)
			(effects
				(font
					(size 0.7 0.7)
					(thickness 0.15)
				)
				(justify right top)
			)
		)
		(fp_text user "License: Apache-2.0"
			(at -0.95 5.169 90)
			(layer "F.Fab")
			(hide yes)
			(effects
				(font
					(size 0.7 0.7)
					(thickness 0.15)
				)
				(justify right top)
			)
		)
		(fp_text user "${REFERENCE}"
			(at -0.95 3.168 90)
			(layer "F.Fab")
			(hide yes)
			(effects
				(font
					(size 0.7 0.7)
					(thickness 0.15)
				)
				(justify right top)
			)
		)
		(pad "1" smd roundrect
			(at -0.48 0 270)
			(size 0.59 0.64)
			(layers "F.Cu" "F.Paste" "F.Mask")
			(roundrect_rratio 0.25)
			(net 134 "Net-(U4-OUT)")
			(pintype "passive")
		)
		(pad "2" smd roundrect
			(at 0.48 0 270)
			(size 0.59 0.64)
			(layers "F.Cu" "F.Paste" "F.Mask")
			(roundrect_rratio 0.25)
			(net 132 "+3V3_OCU")
			(pintype "passive")
		)
	)
	(footprint "antmicro-footprints:TP_SMD_0.75mm"
		(layer "F.Cu")
		(at 116.275 129.5785 180)
		(property "Reference" "TP15"
			(at -0.645 -0.5615 0)
			(layer "F.SilkS")
			(effects
				(font
					(size 0.7 0.7)
					(thickness 0.15)
				)
				(justify right top)
			)
		)
		(property "Value" "TP_0.75mm_SMD"
			(at 0 1.2 0)
			(layer "F.Fab")
			(effects
				(font
					(size 0.7 0.7)
					(thickness 0.15)
				)
				(justify right top)
			)
		)
		(property "Footprint" "antmicro-footprints:TP_SMD_0.75mm"
			(at 0 0 0)
			(layer "F.Fab")
			(hide yes)
			(effects
				(font
					(size 1.27 1.27)
					(thickness 0.15)
				)
			)
		)
		(property "Description" "SMT test point"
			(at 0 0 0)
			(layer "F.Fab")
			(hide yes)
			(effects
				(font
					(size 1.27 1.27)
					(thickness 0.15)
				)
			)
		)
		(property "MPN" ""
			(at 0 0 180)
			(unlocked yes)
			(layer "F.Fab")
			(hide yes)
			(effects
				(font
					(size 1 1)
					(thickness 0.15)
				)
			)
		)
		(property "Manufacturer" ""
			(at 0 0 180)
			(unlocked yes)
			(layer "F.Fab")
			(hide yes)
			(effects
				(font
					(size 1 1)
					(thickness 0.15)
				)
			)
		)
		(property "Author" "Antmicro"
			(at 0 0 180)
			(unlocked yes)
			(layer "F.Fab")
			(hide yes)
			(effects
				(font
					(size 1 1)
					(thickness 0.15)
				)
			)
		)
		(property "License" "Apache-2.0"
			(at 0 0 180)
			(unlocked yes)
			(layer "F.Fab")
			(hide yes)
			(effects
				(font
					(size 1 1)
					(thickness 0.15)
				)
			)
		)
		(property "Public" "False"
			(at 0 0 180)
			(unlocked yes)
			(layer "F.Fab")
			(hide yes)
			(effects
				(font
					(size 1 1)
					(thickness 0.15)
				)
			)
		)
		(sheetname "Root")
		(sheetfile "jetson-orin-baseboard-oculink-expansion.kicad_sch")
		(attr exclude_from_pos_files exclude_from_bom)
		(fp_circle
			(center 0 0)
			(end 0.475 0)
			(stroke
				(width 0.05)
				(type default)
			)
			(fill none)
			(layer "F.CrtYd")
		)
		(fp_text user "${REFERENCE}"
			(at -0.4 2.7 0)
			(layer "F.Fab")
			(hide yes)
			(effects
				(font
					(size 0.7 0.7)
					(thickness 0.15)
				)
				(justify right top)
			)
		)
		(fp_text user "Author: Antmicro"
			(at -0.4 3.901 0)
			(layer "F.Fab")
			(hide yes)
			(effects
				(font
					(size 0.7 0.7)
					(thickness 0.15)
				)
				(justify right top)
			)
		)
		(fp_text user "License: Apache-2.0"
			(at -0.4 5.101 0)
			(layer "F.Fab")
			(hide yes)
			(effects
				(font
					(size 0.7 0.7)
					(thickness 0.15)
				)
				(justify right top)
			)
		)
		(pad "1" smd circle
			(at 0 0 180)
			(size 0.75 0.75)
			(layers "F.Cu" "F.Mask")
			(net 111 "Net-(U3-I2C_{DONE})")
			(pinfunction "1")
			(pintype "passive")
		)
	)
	(footprint "antmicro-footprints:C_0805_2012Metric"
		(layer "F.Cu")
		(at 143.6 119.25)
		(descr "Capacitor SMD 0805")
		(tags "capacitor SMD 0805")
		(property "Reference" "C36"
			(at -1.05 -0.85 0)
			(layer "F.SilkS")
			(effects
				(font
					(size 0.7 0.7)
					(thickness 0.15)
				)
				(justify left bottom)
			)
		)
		(property "Value" "C_100u_0805"
			(at -2.055717 1.963152 0)
			(layer "F.Fab")
			(effects
				(font
					(size 0.7 0.7)
					(thickness 0.15)
				)
				(justify left bottom)
			)
		)
		(property "Footprint" "antmicro-footprints:C_0805_2012Metric"
			(at 0 0 0)
			(layer "F.Fab")
			(hide yes)
			(effects
				(font
					(size 1.27 1.27)
					(thickness 0.15)
				)
			)
		)
		(property "Datasheet" "https://www.murata.com/products/productdetail?partno=GRM21BR60J107ME15%23"
			(at 0 0 0)
			(layer "F.Fab")
			(hide yes)
			(effects
				(font
					(size 1.27 1.27)
					(thickness 0.15)
				)
			)
		)
		(property "Description" "SMD Multilayer Ceramic Capacitor, 100 µF, 6.3 V, 0805 [2012 Metric], ± 20%, X5R, GRM Series"
			(at 0 0 0)
			(layer "F.Fab")
			(hide yes)
			(effects
				(font
					(size 1.27 1.27)
					(thickness 0.15)
				)
			)
		)
		(property "MPN" "GRM21BR60J107ME15L"
			(at 0 0 0)
			(unlocked yes)
			(layer "F.Fab")
			(hide yes)
			(effects
				(font
					(size 1 1)
					(thickness 0.15)
				)
			)
		)
		(property "Manufacturer" "Murata"
			(at 0 0 0)
			(unlocked yes)
			(layer "F.Fab")
			(hide yes)
			(effects
				(font
					(size 1 1)
					(thickness 0.15)
				)
			)
		)
		(property "License" "Apache-2.0"
			(at 0 0 0)
			(unlocked yes)
			(layer "F.Fab")
			(hide yes)
			(effects
				(font
					(size 1 1)
					(thickness 0.15)
				)
			)
		)
		(property "Author" "Antmicro"
			(at 0 0 0)
			(unlocked yes)
			(layer "F.Fab")
			(hide yes)
			(effects
				(font
					(size 1 1)
					(thickness 0.15)
				)
			)
		)
		(property "Val" "100u"
			(at 0 0 0)
			(unlocked yes)
			(layer "F.Fab")
			(hide yes)
			(effects
				(font
					(size 1 1)
					(thickness 0.15)
				)
			)
		)
		(property "Voltage" ""
			(at 0 0 0)
			(unlocked yes)
			(layer "F.Fab")
			(hide yes)
			(effects
				(font
					(size 1 1)
					(thickness 0.15)
				)
			)
		)
		(property "Dielectric" ""
			(at 0 0 0)
			(unlocked yes)
			(layer "F.Fab")
			(hide yes)
			(effects
				(font
					(size 1 1)
					(thickness 0.15)
				)
			)
		)
		(property "Public" "False"
			(at 0 0 0)
			(unlocked yes)
			(layer "F.Fab")
			(hide yes)
			(effects
				(font
					(size 1 1)
					(thickness 0.15)
				)
			)
		)
		(sheetname "Root")
		(sheetfile "jetson-orin-baseboard-oculink-expansion.kicad_sch")
		(attr smd)
		(fp_line
			(start -0.3 -0.7)
			(end 0.3 -0.7)
			(stroke
				(width 0.15)
				(type solid)
			)
			(layer "F.SilkS")
		)
		(fp_line
			(start -0.3 0.7)
			(end 0.3 0.7)
			(stroke
				(width 0.15)
				(type solid)
			)
			(layer "F.SilkS")
		)
		(fp_rect
			(start 1.95 -0.9)
			(end -1.95 0.9)
			(stroke
				(width 0.05)
				(type default)
			)
			(fill none)
			(layer "F.CrtYd")
		)
		(fp_rect
			(start -0.95 -0.675)
			(end 0.95 0.675)
			(stroke
				(width 0.15)
				(type solid)
			)
			(fill none)
			(layer "F.Fab")
		)
		(fp_text user "Author: Antmicro"
			(at -1.9 5.947 0)
			(layer "F.Fab")
			(hide yes)
			(effects
				(font
					(size 0.7 0.7)
					(thickness 0.15)
				)
				(justify left bottom)
			)
		)
		(fp_text user "License: Apache-2.0"
			(at -1.9 4.947 0)
			(layer "F.Fab")
			(hide yes)
			(effects
				(font
					(size 0.7 0.7)
					(thickness 0.15)
				)
				(justify left bottom)
			)
		)
		(fp_text user "${REFERENCE}"
			(at -1.9 3.947 0)
			(layer "F.Fab")
			(hide yes)
			(effects
				(font
					(size 0.7 0.7)
					(thickness 0.15)
				)
				(justify left bottom)
			)
		)
		(pad "1" smd roundrect
			(at -1.1 0)
			(size 1.2 1.3)
			(layers "F.Cu" "F.Paste" "F.Mask")
			(roundrect_rratio 0.25)
			(net 51 "GND")
			(pintype "passive")
		)
		(pad "2" smd roundrect
			(at 1.1 0)
			(size 1.2 1.3)
			(layers "F.Cu" "F.Paste" "F.Mask")
			(roundrect_rratio 0.25)
			(net 135 "Net-(U5-OUT)")
			(pintype "passive")
		)
	)
	(footprint "antmicro-footprints:C_0402_1005Metric"
		(layer "F.Cu")
		(at 113.5 141.25)
		(descr "Capacitor SMD 0402")
		(tags "capacitor SMD 0402")
		(property "Reference" "C4"
			(at -0.8 -0.45 0)
			(layer "F.SilkS")
			(effects
				(font
					(size 0.7 0.7)
					(thickness 0.15)
				)
				(justify left bottom)
			)
		)
		(property "Value" "C_10u_0402"
			(at -1.022927 2.155213 0)
			(layer "F.Fab")
			(effects
				(font
					(size 0.7 0.7)
					(thickness 0.15)
				)
				(justify left bottom)
			)
		)
		(property "Footprint" "antmicro-footprints:C_0402_1005Metric"
			(at 0 0 0)
			(layer "F.Fab")
			(hide yes)
			(effects
				(font
					(size 1.27 1.27)
					(thickness 0.15)
				)
			)
		)
		(property "Datasheet" "https://www.yageo.com/en/Chart/Download/pdf/CC0402MRX5R5BB106"
			(at 0 0 0)
			(layer "F.Fab")
			(hide yes)
			(effects
				(font
					(size 1.27 1.27)
					(thickness 0.15)
				)
			)
		)
		(property "Description" "SMD Multilayer Ceramic Capacitor, 10 µF, 6.3 V, 0402 [1005 Metric], ± 20%, X5R, CC Series"
			(at 0 0 0)
			(layer "F.Fab")
			(hide yes)
			(effects
				(font
					(size 1.27 1.27)
					(thickness 0.15)
				)
			)
		)
		(property "MPN" "CC0402MRX5R5BB106"
			(at 0 0 0)
			(unlocked yes)
			(layer "F.Fab")
			(hide yes)
			(effects
				(font
					(size 1 1)
					(thickness 0.15)
				)
			)
		)
		(property "Manufacturer" "YAGEO"
			(at 0 0 0)
			(unlocked yes)
			(layer "F.Fab")
			(hide yes)
			(effects
				(font
					(size 1 1)
					(thickness 0.15)
				)
			)
		)
		(property "License" "Apache-2.0"
			(at 0 0 0)
			(unlocked yes)
			(layer "F.Fab")
			(hide yes)
			(effects
				(font
					(size 1 1)
					(thickness 0.15)
				)
			)
		)
		(property "Author" "Antmicro"
			(at 0 0 0)
			(unlocked yes)
			(layer "F.Fab")
			(hide yes)
			(effects
				(font
					(size 1 1)
					(thickness 0.15)
				)
			)
		)
		(property "Val" "10u"
			(at 0 0 0)
			(unlocked yes)
			(layer "F.Fab")
			(hide yes)
			(effects
				(font
					(size 1 1)
					(thickness 0.15)
				)
			)
		)
		(property "Voltage" ""
			(at 0 0 0)
			(unlocked yes)
			(layer "F.Fab")
			(hide yes)
			(effects
				(font
					(size 1 1)
					(thickness 0.15)
				)
			)
		)
		(property "Dielectric" ""
			(at 0 0 0)
			(unlocked yes)
			(layer "F.Fab")
			(hide yes)
			(effects
				(font
					(size 1 1)
					(thickness 0.15)
				)
			)
		)
		(sheetname "Root")
		(sheetfile "jetson-orin-baseboard-oculink-expansion.kicad_sch")
		(attr smd)
		(fp_rect
			(start -0.925 -0.47)
			(end 0.925 0.47)
			(stroke
				(width 0.05)
				(type default)
			)
			(fill none)
			(layer "F.CrtYd")
		)
		(fp_line
			(start -0.494 -0.25)
			(end 0.504 -0.25)
			(stroke
				(width 0.15)
				(type solid)
			)
			(layer "F.Fab")
		)
		(fp_line
			(start -0.494 0.248)
			(end -0.494 -0.25)
			(stroke
				(width 0.15)
				(type solid)
			)
			(layer "F.Fab")
		)
		(fp_line
			(start 0.504 -0.25)
			(end 0.504 0.248)
			(stroke
				(width 0.15)
				(type solid)
			)
			(layer "F.Fab")
		)
		(fp_line
			(start 0.504 0.248)
			(end -0.494 0.248)
			(stroke
				(width 0.15)
				(type solid)
			)
			(layer "F.Fab")
		)
		(fp_text user "License: Apache-2.0"
			(at -0.939 5.799 0)
			(layer "F.Fab")
			(hide yes)
			(effects
				(font
					(size 0.7 0.7)
					(thickness 0.15)
				)
				(justify left bottom)
			)
		)
		(fp_text user "Author: Antmicro"
			(at -0.939 3.399 0)
			(layer "F.Fab")
			(hide yes)
			(effects
				(font
					(size 0.7 0.7)
					(thickness 0.15)
				)
				(justify left bottom)
			)
		)
		(fp_text user "${REFERENCE}"
			(at -0.939 4.599 0)
			(layer "F.Fab")
			(hide yes)
			(effects
				(font
					(size 0.7 0.7)
					(thickness 0.15)
				)
				(justify left bottom)
			)
		)
		(pad "1" smd roundrect
			(at -0.48 0)
			(size 0.59 0.64)
			(layers "F.Cu" "F.Paste" "F.Mask")
			(roundrect_rratio 0.25)
			(net 51 "GND")
			(pintype "passive")
		)
		(pad "2" smd roundrect
			(at 0.48 0)
			(size 0.59 0.64)
			(layers "F.Cu" "F.Paste" "F.Mask")
			(roundrect_rratio 0.25)
			(net 133 "+5V_OCU")
			(pintype "passive")
		)
	)
	(footprint "antmicro-footprints:C_0402_1005Metric"
		(layer "F.Cu")
		(at 144.467 121.671)
		(descr "Capacitor SMD 0402")
		(tags "capacitor SMD 0402")
		(property "Reference" "C34"
			(at -1.017 -0.471 0)
			(layer "F.SilkS")
			(effects
				(font
					(size 0.7 0.7)
					(thickness 0.15)
				)
				(justify left bottom)
			)
		)
		(property "Value" "C_100n_0402"
			(at -1.022927 2.155213 0)
			(layer "F.Fab")
			(effects
				(font
					(size 0.7 0.7)
					(thickness 0.15)
				)
				(justify left bottom)
			)
		)
		(property "Footprint" "antmicro-footprints:C_0402_1005Metric"
			(at 0 0 0)
			(layer "F.Fab")
			(hide yes)
			(effects
				(font
					(size 1.27 1.27)
					(thickness 0.15)
				)
			)
		)
		(property "Datasheet" "https://www.murata.com/products/productdetail?partno=GRM155R61H104KE14%23"
			(at 0 0 0)
			(layer "F.Fab")
			(hide yes)
			(effects
				(font
					(size 1.27 1.27)
					(thickness 0.15)
				)
			)
		)
		(property "Description" "SMD Multilayer Ceramic Capacitor, 0.1 µF, 50 V, 0402 [1005 Metric], ± 10%, X5R, GRM Series"
			(at 0 0 0)
			(layer "F.Fab")
			(hide yes)
			(effects
				(font
					(size 1.27 1.27)
					(thickness 0.15)
				)
			)
		)
		(property "MPN" "GRM155R61H104KE14D"
			(at 0 0 0)
			(unlocked yes)
			(layer "F.Fab")
			(hide yes)
			(effects
				(font
					(size 1 1)
					(thickness 0.15)
				)
			)
		)
		(property "Manufacturer" "Murata"
			(at 0 0 0)
			(unlocked yes)
			(layer "F.Fab")
			(hide yes)
			(effects
				(font
					(size 1 1)
					(thickness 0.15)
				)
			)
		)
		(property "License" "Apache-2.0"
			(at 0 0 0)
			(unlocked yes)
			(layer "F.Fab")
			(hide yes)
			(effects
				(font
					(size 1 1)
					(thickness 0.15)
				)
			)
		)
		(property "Author" "Antmicro"
			(at 0 0 0)
			(unlocked yes)
			(layer "F.Fab")
			(hide yes)
			(effects
				(font
					(size 1 1)
					(thickness 0.15)
				)
			)
		)
		(property "Val" "100n"
			(at 0 0 0)
			(unlocked yes)
			(layer "F.Fab")
			(hide yes)
			(effects
				(font
					(size 1 1)
					(thickness 0.15)
				)
			)
		)
		(property "Voltage" "50V"
			(at 0 0 0)
			(unlocked yes)
			(layer "F.Fab")
			(hide yes)
			(effects
				(font
					(size 1 1)
					(thickness 0.15)
				)
			)
		)
		(property "Dielectric" "X5R"
			(at 0 0 0)
			(unlocked yes)
			(layer "F.Fab")
			(hide yes)
			(effects
				(font
					(size 1 1)
					(thickness 0.15)
				)
			)
		)
		(sheetname "Root")
		(sheetfile "jetson-orin-baseboard-oculink-expansion.kicad_sch")
		(attr smd)
		(fp_rect
			(start -0.925 -0.47)
			(end 0.925 0.47)
			(stroke
				(width 0.05)
				(type default)
			)
			(fill none)
			(layer "F.CrtYd")
		)
		(fp_line
			(start -0.494 -0.25)
			(end 0.504 -0.25)
			(stroke
				(width 0.15)
				(type solid)
			)
			(layer "F.Fab")
		)
		(fp_line
			(start -0.494 0.248)
			(end -0.494 -0.25)
			(stroke
				(width 0.15)
				(type solid)
			)
			(layer "F.Fab")
		)
		(fp_line
			(start 0.504 -0.25)
			(end 0.504 0.248)
			(stroke
				(width 0.15)
				(type solid)
			)
			(layer "F.Fab")
		)
		(fp_line
			(start 0.504 0.248)
			(end -0.494 0.248)
			(stroke
				(width 0.15)
				(type solid)
			)
			(layer "F.Fab")
		)
		(fp_text user "License: Apache-2.0"
			(at -0.939 5.799 0)
			(layer "F.Fab")
			(hide yes)
			(effects
				(font
					(size 0.7 0.7)
					(thickness 0.15)
				)
				(justify left bottom)
			)
		)
		(fp_text user "Author: Antmicro"
			(at -0.939 3.399 0)
			(layer "F.Fab")
			(hide yes)
			(effects
				(font
					(size 0.7 0.7)
					(thickness 0.15)
				)
				(justify left bottom)
			)
		)
		(fp_text user "${REFERENCE}"
			(at -0.939 4.599 0)
			(layer "F.Fab")
			(hide yes)
			(effects
				(font
					(size 0.7 0.7)
					(thickness 0.15)
				)
				(justify left bottom)
			)
		)
		(pad "1" smd roundrect
			(at -0.48 0)
			(size 0.59 0.64)
			(layers "F.Cu" "F.Paste" "F.Mask")
			(roundrect_rratio 0.25)
			(net 51 "GND")
			(pintype "passive")
		)
		(pad "2" smd roundrect
			(at 0.48 0)
			(size 0.59 0.64)
			(layers "F.Cu" "F.Paste" "F.Mask")
			(roundrect_rratio 0.25)
			(net 135 "Net-(U5-OUT)")
			(pintype "passive")
		)
	)
)
